# T6G (Grand Teton) — schematic netlist excerpt (pin names and nets, part order shuffled) for the footprints in the layout excerpt that follows; sources: Cadence DE-HDL packaged netlist, KiCad conversion of 04192023_DAF0TMB3IC0_F0TG_MB_C_brd_V02_OCP.brd

R948  Q_RES  130 1% CHIP  pkg 0402LF  page 166 : A = PU_BOOT_RDY_LED ; B = P3V3_AUX
C2021  Q_CAP  0.1UF 25V 10% X7R  pkg 0402  page 237 : A = VSENSE_P12V_INA230_4_INP ; B = VSENSE_P12V_INA230_4_INN

(kicad_pcb
	(version 20260206)
	(generator "pcbnew")
	(generator_version "10.0")
	(general
		(thickness 1.6)
		(legacy_teardrops no)
	)
	(paper "A4")
	(title_block
		(title "04192023_DAF0TMB3IC0_F0TG_MB_C_brd_V02_OCP.brd")
		(comment 1 "Grand Teton / footprints 2869-2870 of 8354")
	)
	(layers
		(0 "F.Cu" signal "TOP")
		(4 "In1.Cu" signal "GND")
		(6 "In2.Cu" signal "IN1")
		(8 "In3.Cu" signal "GND1")
		(10 "In4.Cu" signal "IN2")
		(12 "In5.Cu" signal "GND2")
		(14 "In6.Cu" signal "IN3")
		(16 "In7.Cu" signal "GND3")
		(18 "In8.Cu" signal "VCC")
		(20 "In9.Cu" signal "VCC1")
		(22 "In10.Cu" signal "GND4")
		(24 "In11.Cu" signal "IN4")
		(26 "In12.Cu" signal "GND5")
		(28 "In13.Cu" signal "IN5")
		(30 "In14.Cu" signal "GND6")
		(32 "In15.Cu" signal "IN6")
		(34 "In16.Cu" signal "GND7")
		(2 "B.Cu" signal "BOTTOM")
		(9 "F.Adhes" user "F.Adhesive")
		(11 "B.Adhes" user "B.Adhesive")
		(13 "F.Paste" user "Package Geometry/Pastemask Top")
		(15 "B.Paste" user "Package Geometry/Pastemask Bottom")
		(5 "F.SilkS" user "Ref Des/Silkscreen Top")
		(7 "B.SilkS" user "Ref Des/Silkscreen Bottom")
		(1 "F.Mask" user "Board Geometry/Soldermask Top")
		(3 "B.Mask" user "Board Geometry/Soldermask Bottom")
		(17 "Dwgs.User" user "User.Drawings")
		(19 "Cmts.User" user "User.Comments")
		(21 "Eco1.User" user "User.Eco1")
		(23 "Eco2.User" user "User.Eco2")
		(25 "Edge.Cuts" user "Board Geometry/Outline")
		(27 "Margin" user)
		(31 "F.CrtYd" user "Package Geometry/Place Bound Top")
		(29 "B.CrtYd" user "Package Geometry/Place Bound Bottom")
		(35 "F.Fab" user "Ref Des/Assembly Top")
		(33 "B.Fab" user "Ref Des/Assembly Bottom")
	)
	(footprint ""
		(layer "F.Cu")
		(at 338.31022 -15.98803 90)
		(property "Reference" "R948"
			(at 0 0 90)
			(layer "F.SilkS")
			(hide yes)
			(effects
				(font
					(size 1.27 1.27)
				)
			)
		)
		(property "Value" ""
			(at 0 0 90)
			(layer "F.Fab")
			(effects
				(font
					(size 1.27 1.27)
				)
			)
		)
		(duplicate_pad_numbers_are_jumpers no)
		(fp_line
			(start 0.7874 -0.4064)
			(end 0.7874 0.4064)
			(stroke
				(width 0.1524)
				(type default)
			)
			(layer "F.SilkS")
		)
		(fp_line
			(start -0.7874 -0.4064)
			(end 0.7874 -0.4064)
			(stroke
				(width 0.1524)
				(type default)
			)
			(layer "F.SilkS")
		)
		(fp_line
			(start 0.7874 0.4064)
			(end -0.7874 0.4064)
			(stroke
				(width 0.1524)
				(type default)
			)
			(layer "F.SilkS")
		)
		(fp_line
			(start -0.7874 0.4064)
			(end -0.7874 -0.4064)
			(stroke
				(width 0.1524)
				(type default)
			)
			(layer "F.SilkS")
		)
		(fp_line
			(start -0.12065 -0.305054)
			(end -0.12065 -0.2794)
			(stroke
				(width 0.1)
				(type default)
			)
			(layer "F.Fab")
		)
		(fp_line
			(start -0.67945 -0.305054)
			(end -0.12065 -0.305054)
			(stroke
				(width 0.1)
				(type default)
			)
			(layer "F.Fab")
		)
		(fp_line
			(start 0.67945 -0.3048)
			(end 0.67945 0.3048)
			(stroke
				(width 0.1)
				(type default)
			)
			(layer "F.Fab")
		)
		(fp_line
			(start 0.12065 -0.3048)
			(end 0.67945 -0.3048)
			(stroke
				(width 0.1)
				(type default)
			)
			(layer "F.Fab")
		)
		(fp_line
			(start 0.12065 -0.2794)
			(end 0.12065 -0.3048)
			(stroke
				(width 0.1)
				(type default)
			)
			(layer "F.Fab")
		)
		(fp_line
			(start -0.12065 -0.2794)
			(end 0.12065 -0.2794)
			(stroke
				(width 0.1)
				(type default)
			)
			(layer "F.Fab")
		)
		(fp_line
			(start 0.120396 0.2794)
			(end -0.12065 0.2794)
			(stroke
				(width 0.1)
				(type default)
			)
			(layer "F.Fab")
		)
		(fp_line
			(start -0.12065 0.2794)
			(end -0.12065 0.3048)
			(stroke
				(width 0.1)
				(type default)
			)
			(layer "F.Fab")
		)
		(fp_line
			(start 0.67945 0.3048)
			(end 0.120396 0.3048)
			(stroke
				(width 0.1)
				(type default)
			)
			(layer "F.Fab")
		)
		(fp_line
			(start 0.120396 0.3048)
			(end 0.120396 0.2794)
			(stroke
				(width 0.1)
				(type default)
			)
			(layer "F.Fab")
		)
		(fp_line
			(start -0.12065 0.3048)
			(end -0.67945 0.3048)
			(stroke
				(width 0.1)
				(type default)
			)
			(layer "F.Fab")
		)
		(fp_line
			(start -0.67945 0.3048)
			(end -0.67945 -0.305054)
			(stroke
				(width 0.1)
				(type default)
			)
			(layer "F.Fab")
		)
		(pad "1" smd circle
			(at -0.40005 0 90)
			(size 0 0)
			(layers "F.Cu" "F.Mask" "F.Paste")
			(net "PU_BOOT_RDY_LED")
		)
		(pad "2" smd circle
			(at 0.40005 0 90)
			(size 0 0)
			(layers "F.Cu" "F.Mask" "F.Paste")
			(net "P3V3_AUX")
		)
	)
	(footprint ""
		(layer "F.Cu")
		(at 160.174686 -58.15965 -90)
		(property "Reference" "C2021"
			(at 0 0 270)
			(layer "F.SilkS")
			(hide yes)
			(effects
				(font
					(size 1.27 1.27)
				)
			)
		)
		(property "Value" ""
			(at 0 0 270)
			(layer "F.Fab")
			(effects
				(font
					(size 1.27 1.27)
				)
			)
		)
		(duplicate_pad_numbers_are_jumpers no)
		(fp_line
			(start -0.7874 0.4064)
			(end -0.7874 -0.4064)
			(stroke
				(width 0.1524)
				(type default)
			)
			(layer "F.SilkS")
		)
		(fp_line
			(start 0.7874 0.4064)
			(end -0.7874 0.4064)
			(stroke
				(width 0.1524)
				(type default)
			)
			(layer "F.SilkS")
		)
		(fp_line
			(start -0.7874 -0.4064)
			(end 0.7874 -0.4064)
			(stroke
				(width 0.1524)
				(type default)
			)
			(layer "F.SilkS")
		)
		(fp_line
			(start 0.7874 -0.4064)
			(end 0.7874 0.4064)
			(stroke
				(width 0.1524)
				(type default)
			)
			(layer "F.SilkS")
		)
		(fp_line
			(start -0.67945 0.3048)
			(end -0.67945 -0.305054)
			(stroke
				(width 0.1)
				(type default)
			)
			(layer "F.Fab")
		)
		(fp_line
			(start -0.12065 0.3048)
			(end -0.67945 0.3048)
			(stroke
				(width 0.1)
				(type default)
			)
			(layer "F.Fab")
		)
		(fp_line
			(start 0.120396 0.3048)
			(end 0.120396 0.2794)
			(stroke
				(width 0.1)
				(type default)
			)
			(layer "F.Fab")
		)
		(fp_line
			(start 0.67945 0.3048)
			(end 0.120396 0.3048)
			(stroke
				(width 0.1)
				(type default)
			)
			(layer "F.Fab")
		)
		(fp_line
			(start -0.12065 0.2794)
			(end -0.12065 0.3048)
			(stroke
				(width 0.1)
				(type default)
			)
			(layer "F.Fab")
		)
		(fp_line
			(start 0.120396 0.2794)
			(end -0.12065 0.2794)
			(stroke
				(width 0.1)
				(type default)
			)
			(layer "F.Fab")
		)
		(fp_line
			(start -0.12065 -0.2794)
			(end 0.12065 -0.2794)
			(stroke
				(width 0.1)
				(type default)
			)
			(layer "F.Fab")
		)
		(fp_line
			(start 0.12065 -0.2794)
			(end 0.12065 -0.3048)
			(stroke
				(width 0.1)
				(type default)
			)
			(layer "F.Fab")
		)
		(fp_line
			(start 0.12065 -0.3048)
			(end 0.67945 -0.3048)
			(stroke
				(width 0.1)
				(type default)
			)
			(layer "F.Fab")
		)
		(fp_line
			(start 0.67945 -0.3048)
			(end 0.67945 0.3048)
			(stroke
				(width 0.1)
				(type default)
			)
			(layer "F.Fab")
		)
		(fp_line
			(start -0.67945 -0.305054)
			(end -0.12065 -0.305054)
			(stroke
				(width 0.1)
				(type default)
			)
			(layer "F.Fab")
		)
		(fp_line
			(start -0.12065 -0.305054)
			(end -0.12065 -0.2794)
			(stroke
				(width 0.1)
				(type default)
			)
			(layer "F.Fab")
		)
		(pad "1" smd circle
			(at -0.40005 0 270)
			(size 0 0)
			(layers "F.Cu" "F.Mask" "F.Paste")
			(net "VSENSE_P12V_INA230_4_INP")
		)
		(pad "2" smd circle
			(at 0.40005 0 270)
			(size 0 0)
			(layers "F.Cu" "F.Mask" "F.Paste")
			(net "VSENSE_P12V_INA230_4_INN")
		)
	)
)
